(kicad_pcb
	(version 20260206)
	(generator "pcbnew")
	(generator_version "10.0")
	(general
		(thickness 1.6)
		(legacy_teardrops no)
	)
	(paper "A4")
	(title_block
		(title "peb — Lightning_PEB_BRD.brd")
		(comment 1 "Lightning (Wiwynn / Facebook NVMe JBOF) / footprints 1639-1646 of 2563")
	)
	(layers
		(0 "F.Cu" signal "TOP")
		(4 "In1.Cu" signal "L2GND")
		(6 "In2.Cu" signal "L3")
		(8 "In3.Cu" signal "L4VCC")
		(10 "In4.Cu" signal "L5VCC")
		(12 "In5.Cu" signal "L6")
		(14 "In6.Cu" signal "L7GND")
		(2 "B.Cu" signal "BOTTOM")
		(9 "F.Adhes" user "F.Adhesive")
		(11 "B.Adhes" user "B.Adhesive")
		(13 "F.Paste" user "Package Geometry/Pastemask Top")
		(15 "B.Paste" user "Package Geometry/Pastemask Bottom")
		(5 "F.SilkS" user "Ref Des/Silkscreen Top")
		(7 "B.SilkS" user "Ref Des/Silkscreen Bottom")
		(1 "F.Mask" user "Board Geometry/Soldermask Top")
		(3 "B.Mask" user "Board Geometry/Soldermask Bottom")
		(17 "Dwgs.User" user "User.Drawings")
		(19 "Cmts.User" user "User.Comments")
		(21 "Eco1.User" user "User.Eco1")
		(23 "Eco2.User" user "User.Eco2")
		(25 "Edge.Cuts" user "Board Geometry/Outline")
		(27 "Margin" user)
		(31 "F.CrtYd" user "Package Geometry/Place Bound Top")
		(29 "B.CrtYd" user "Package Geometry/Place Bound Bottom")
		(35 "F.Fab" user "Ref Des/Assembly Top")
		(33 "B.Fab" user "Ref Des/Assembly Bottom")
	)
	(footprint ""
		(layer "F.Cu")
		(at 24.2951 -50.6476 90)
		(property "Reference" "D19"
			(at 0 0 90)
			(layer "F.SilkS")
			(hide yes)
			(effects
				(font
					(size 1.27 1.27)
				)
			)
		)
		(property "Value" "PGB1010603MR-GP"
			(at -0.0254 -2.8956 90)
			(unlocked yes)
			(layer "F.Fab")
			(hide yes)
			(effects
				(font
					(size 1.016 1.016)
					(thickness 0.1524)
				)
			)
		)
		(property "Device Type" "L1608-UH15"
			(at -0.0254 -4.4196 90)
			(unlocked yes)
			(layer "F.Fab")
			(hide yes)
			(effects
				(font
					(size 1.016 1.016)
					(thickness 0.1524)
				)
			)
		)
		(duplicate_pad_numbers_are_jumpers no)
		(fp_line
			(start 0.254 0)
			(end -0.254 0)
			(stroke
				(width 0.2032)
				(type default)
			)
			(layer "F.SilkS")
		)
		(fp_rect
			(start -0.5842 1.3335)
			(end 0.5842 -1.3335)
			(stroke
				(width 0)
				(type default)
			)
			(fill no)
			(layer "F.CrtYd")
		)
		(fp_rect
			(start -0.5842 1.3335)
			(end 0.5842 -1.3335)
			(stroke
				(width 0)
				(type default)
			)
			(fill no)
			(layer "F.Fab")
		)
		(pad "1" smd custom
			(at 0 -0.762 90)
			(size 0.2159 0.2159)
			(layers "F.Cu" "F.Mask" "F.Paste")
			(net "NIC0_MDI0_P3_R")
			(options
				(clearance outline)
				(anchor circle)
			)
			(primitives
				(gr_poly
					(pts
						(arc
							(start -0.3302 -0.4318)
							(mid -0.402042 -0.402042)
							(end -0.4318 -0.3302)
						)
						(arc
							(start -0.4318 0.3302)
							(mid -0.402042 0.402042)
							(end -0.3302 0.4318)
						)
						(arc
							(start 0.3302 0.4318)
							(mid 0.402042 0.402042)
							(end 0.4318 0.3302)
						)
						(arc
							(start 0.4318 -0.3302)
							(mid 0.402042 -0.402042)
							(end 0.3302 -0.4318)
						)
					)
					(width 0)
					(fill yes)
				)
			)
		)
		(pad "2" smd custom
			(at 0 0.762 90)
			(size 0.2159 0.2159)
			(layers "F.Cu" "F.Mask" "F.Paste")
			(net "GND")
			(options
				(clearance outline)
				(anchor circle)
			)
			(primitives
				(gr_poly
					(pts
						(arc
							(start -0.3302 -0.4318)
							(mid -0.402042 -0.402042)
							(end -0.4318 -0.3302)
						)
						(arc
							(start -0.4318 0.3302)
							(mid -0.402042 0.402042)
							(end -0.3302 0.4318)
						)
						(arc
							(start 0.3302 0.4318)
							(mid 0.402042 0.402042)
							(end 0.4318 0.3302)
						)
						(arc
							(start 0.4318 -0.3302)
							(mid 0.402042 -0.402042)
							(end 0.3302 -0.4318)
						)
					)
					(width 0)
					(fill yes)
				)
			)
		)
	)
	(footprint ""
		(layer "F.Cu")
		(at 335.153 -184.404)
		(property "Reference" "TP184"
			(at 0 0 0)
			(layer "F.SilkS")
			(hide yes)
			(effects
				(font
					(size 1.27 1.27)
				)
			)
		)
		(property "Value" "TPAD28-2-GP"
			(at -0.0127 -1.6637 0)
			(unlocked yes)
			(layer "F.Fab")
			(hide yes)
			(effects
				(font
					(size 1.016 1.016)
					(thickness 0.1524)
				)
			)
		)
		(property "Device Type" "TPAD28"
			(at -0.0127 -3.1877 0)
			(unlocked yes)
			(layer "F.Fab")
			(hide yes)
			(effects
				(font
					(size 1.016 1.016)
					(thickness 0.1524)
				)
			)
		)
		(duplicate_pad_numbers_are_jumpers no)
		(fp_poly
			(pts
				(arc
					(start 0.3556 0)
					(mid -0.3556 0)
					(end 0.3556 0)
				)
			)
			(stroke
				(width 0)
				(type default)
			)
			(fill no)
			(layer "F.CrtYd")
		)
		(fp_poly
			(pts
				(arc
					(start 0.6096 0)
					(mid -0.6096 0)
					(end 0.6096 0)
				)
			)
			(stroke
				(width 0)
				(type default)
			)
			(fill no)
			(layer "F.Fab")
		)
		(pad "1" smd circle
			(at 0 0)
			(size 0.7112 0.7112)
			(layers "F.Cu" "F.Mask" "F.Paste")
			(net "IOEXP4_GPIO14")
		)
	)
	(footprint ""
		(layer "F.Cu")
		(at 48.641 -150.495 180)
		(property "Reference" "R161"
			(at 0 0 180)
			(layer "F.SilkS")
			(hide yes)
			(effects
				(font
					(size 1.27 1.27)
				)
			)
		)
		(property "Value" "4K7R2F-GP"
			(at 0.064008 -3.993896 180)
			(unlocked yes)
			(layer "F.Fab")
			(hide yes)
			(effects
				(font
					(size 1.016 1.016)
					(thickness 0.1524)
				)
			)
		)
		(property "Device Type" "R402H16"
			(at 0.064008 -5.517896 180)
			(unlocked yes)
			(layer "F.Fab")
			(hide yes)
			(effects
				(font
					(size 1.016 1.016)
					(thickness 0.1524)
				)
			)
		)
		(duplicate_pad_numbers_are_jumpers no)
		(fp_line
			(start 0.508 -0.9398)
			(end -0.508 -0.9398)
			(stroke
				(width 0.1524)
				(type default)
			)
			(layer "F.SilkS")
		)
		(fp_line
			(start -0.508 -0.9398)
			(end -0.508 0.9398)
			(stroke
				(width 0.1524)
				(type default)
			)
			(layer "F.SilkS")
		)
		(fp_rect
			(start -0.508 0.9398)
			(end 0.508 -0.9398)
			(stroke
				(width 0)
				(type default)
			)
			(fill no)
			(layer "F.CrtYd")
		)
		(fp_rect
			(start -0.508 0.9398)
			(end 0.508 -0.9398)
			(stroke
				(width 0)
				(type default)
			)
			(fill no)
			(layer "F.Fab")
		)
		(pad "1" smd custom
			(at 0 -0.4445 180)
			(size 0.1397 0.1397)
			(layers "F.Cu" "F.Mask" "F.Paste")
			(net "P3V3_STBY")
			(options
				(clearance outline)
				(anchor circle)
			)
			(primitives
				(gr_poly
					(pts
						(arc
							(start -0.1778 -0.2794)
							(mid -0.249642 -0.249642)
							(end -0.2794 -0.1778)
						)
						(arc
							(start -0.2794 0.1778)
							(mid -0.249642 0.249642)
							(end -0.1778 0.2794)
						)
						(arc
							(start 0.1778 0.2794)
							(mid 0.249642 0.249642)
							(end 0.2794 0.1778)
						)
						(arc
							(start 0.2794 -0.1778)
							(mid 0.249642 -0.249642)
							(end 0.1778 -0.2794)
						)
					)
					(width 0)
					(fill yes)
				)
			)
		)
		(pad "2" smd custom
			(at 0 0.4445 180)
			(size 0.1397 0.1397)
			(layers "F.Cu" "F.Mask" "F.Paste")
			(net "TEMP_2_A1")
			(options
				(clearance outline)
				(anchor circle)
			)
			(primitives
				(gr_poly
					(pts
						(arc
							(start -0.1778 -0.2794)
							(mid -0.249642 -0.249642)
							(end -0.2794 -0.1778)
						)
						(arc
							(start -0.2794 0.1778)
							(mid -0.249642 0.249642)
							(end -0.1778 0.2794)
						)
						(arc
							(start 0.1778 0.2794)
							(mid 0.249642 0.249642)
							(end 0.2794 0.1778)
						)
						(arc
							(start 0.2794 -0.1778)
							(mid 0.249642 -0.249642)
							(end 0.1778 -0.2794)
						)
					)
					(width 0)
					(fill yes)
				)
			)
		)
	)
	(footprint ""
		(layer "F.Cu")
		(at 11.4554 -100.1776 90)
		(property "Reference" "C232"
			(at 0 0 90)
			(layer "F.SilkS")
			(hide yes)
			(effects
				(font
					(size 1.27 1.27)
				)
			)
		)
		(property "Value" "SC1U10V2KX-4-GP"
			(at 1.1811 -2.7051 90)
			(unlocked yes)
			(layer "F.Fab")
			(hide yes)
			(effects
				(font
					(size 1.016 1.016)
					(thickness 0.1524)
				)
			)
		)
		(property "Device Type" "C402H22"
			(at 1.1811 -4.2291 90)
			(unlocked yes)
			(layer "F.Fab")
			(hide yes)
			(effects
				(font
					(size 1.016 1.016)
					(thickness 0.1524)
				)
			)
		)
		(duplicate_pad_numbers_are_jumpers no)
		(fp_rect
			(start -0.4318 0.9525)
			(end 0.4318 -0.9525)
			(stroke
				(width 0)
				(type default)
			)
			(fill no)
			(layer "F.CrtYd")
		)
		(fp_rect
			(start -0.4318 0.9525)
			(end 0.4318 -0.9525)
			(stroke
				(width 0)
				(type default)
			)
			(fill no)
			(layer "F.Fab")
		)
		(pad "1" smd custom
			(at 0 -0.4445 90)
			(size 0.1524 0.1524)
			(layers "F.Cu" "F.Mask" "F.Paste")
			(net "P3V3_STBY")
			(options
				(clearance outline)
				(anchor circle)
			)
			(primitives
				(gr_poly
					(pts
						(arc
							(start 0.3048 -0.2032)
							(mid 0.275042 -0.275042)
							(end 0.2032 -0.3048)
						)
						(arc
							(start -0.2032 -0.3048)
							(mid -0.275042 -0.275042)
							(end -0.3048 -0.2032)
						)
						(arc
							(start -0.3048 0.2032)
							(mid -0.275042 0.275042)
							(end -0.2032 0.3048)
						)
						(arc
							(start 0.2032 0.3048)
							(mid 0.275042 0.275042)
							(end 0.3048 0.2032)
						)
					)
					(width 0)
					(fill yes)
				)
			)
		)
		(pad "2" smd custom
			(at 0 0.4445 90)
			(size 0.1524 0.1524)
			(layers "F.Cu" "F.Mask" "F.Paste")
			(net "GND")
			(options
				(clearance outline)
				(anchor circle)
			)
			(primitives
				(gr_poly
					(pts
						(arc
							(start 0.3048 -0.2032)
							(mid 0.275042 -0.275042)
							(end 0.2032 -0.3048)
						)
						(arc
							(start -0.2032 -0.3048)
							(mid -0.275042 -0.275042)
							(end -0.3048 -0.2032)
						)
						(arc
							(start -0.3048 0.2032)
							(mid -0.275042 0.275042)
							(end -0.2032 0.3048)
						)
						(arc
							(start 0.2032 0.3048)
							(mid 0.275042 0.275042)
							(end 0.3048 0.2032)
						)
					)
					(width 0)
					(fill yes)
				)
			)
		)
	)
	(footprint ""
		(layer "F.Cu")
		(at 37.183314 -65.01892 90)
		(property "Reference" "TC14"
			(at 0 0 90)
			(layer "F.SilkS")
			(hide yes)
			(effects
				(font
					(size 1.27 1.27)
				)
			)
		)
		(property "Value" "SC22U25V6KX-GP-U"
			(at -2.860802 -5.279644 90)
			(unlocked yes)
			(layer "F.Fab")
			(hide yes)
			(effects
				(font
					(size 1.016 1.016)
					(thickness 0.1524)
				)
			)
		)
		(property "Device Type" "C1206-TO0D3H75"
			(at -2.860802 -6.803644 90)
			(unlocked yes)
			(layer "F.Fab")
			(hide yes)
			(effects
				(font
					(size 1.016 1.016)
					(thickness 0.1524)
				)
			)
		)
		(duplicate_pad_numbers_are_jumpers no)
		(fp_line
			(start 1.3081 -2.3749)
			(end 1.3081 2.3749)
			(stroke
				(width 0.1524)
				(type default)
			)
			(layer "F.SilkS")
		)
		(fp_line
			(start -1.3081 -2.3749)
			(end 1.3081 -2.3749)
			(stroke
				(width 0.1524)
				(type default)
			)
			(layer "F.SilkS")
		)
		(fp_line
			(start 1.3081 2.3749)
			(end -1.3081 2.3749)
			(stroke
				(width 0.1524)
				(type default)
			)
			(layer "F.SilkS")
		)
		(fp_line
			(start -1.3081 2.3749)
			(end -1.3081 -2.3749)
			(stroke
				(width 0.1524)
				(type default)
			)
			(layer "F.SilkS")
		)
		(fp_rect
			(start -0.8001 1.6002)
			(end 0.8001 -1.6002)
			(stroke
				(width 0)
				(type default)
			)
			(fill no)
			(layer "F.CrtYd")
		)
		(fp_poly
			(pts
				(xy -1.5621 2.4511) (xy -1.5621 1.6002) (xy 0.8001 1.6002) (xy 0.8001 -1.6002) (xy -0.8001 -1.6002)
				(xy -0.8001 1.5875) (xy -1.5621 1.5875) (xy -1.5621 -2.4511) (xy 1.5621 -2.4511) (xy 1.5621 2.4511)
			)
			(stroke
				(width 0)
				(type default)
			)
			(fill no)
			(layer "F.CrtYd")
		)
		(fp_rect
			(start -1.5621 2.4511)
			(end 1.5621 -2.4511)
			(stroke
				(width 0)
				(type default)
			)
			(fill no)
			(layer "F.Fab")
		)
		(pad "1" smd rect
			(at 0 -1.392936 90)
			(size 2.1082 1.4478)
			(layers "F.Cu" "F.Mask" "F.Paste")
			(net "P5V_USB_BP1_F")
		)
		(pad "2" smd rect
			(at 0 1.392936 90)
			(size 2.1082 1.4478)
			(layers "F.Cu" "F.Mask" "F.Paste")
			(net "GND")
		)
	)
	(footprint ""
		(layer "F.Cu")
		(at 181.61 -25.908 -90)
		(property "Reference" "C406"
			(at 0 0 270)
			(layer "F.SilkS")
			(hide yes)
			(effects
				(font
					(size 1.27 1.27)
				)
			)
		)
		(property "Value" "SCD22U10V2KX-1GP"
			(at 1.1811 -2.7051 270)
			(unlocked yes)
			(layer "F.Fab")
			(hide yes)
			(effects
				(font
					(size 1.016 1.016)
					(thickness 0.1524)
				)
			)
		)
		(property "Device Type" "C402H22"
			(at 1.1811 -4.2291 270)
			(unlocked yes)
			(layer "F.Fab")
			(hide yes)
			(effects
				(font
					(size 1.016 1.016)
					(thickness 0.1524)
				)
			)
		)
		(duplicate_pad_numbers_are_jumpers no)
		(fp_rect
			(start -0.4318 0.9525)
			(end 0.4318 -0.9525)
			(stroke
				(width 0)
				(type default)
			)
			(fill no)
			(layer "F.CrtYd")
		)
		(fp_rect
			(start -0.4318 0.9525)
			(end 0.4318 -0.9525)
			(stroke
				(width 0)
				(type default)
			)
			(fill no)
			(layer "F.Fab")
		)
		(pad "1" smd custom
			(at 0 -0.4445 270)
			(size 0.1524 0.1524)
			(layers "F.Cu" "F.Mask" "F.Paste")
			(net "PCIE_TX_CAP_N93")
			(options
				(clearance outline)
				(anchor circle)
			)
			(primitives
				(gr_poly
					(pts
						(arc
							(start 0.3048 -0.2032)
							(mid 0.275042 -0.275042)
							(end 0.2032 -0.3048)
						)
						(arc
							(start -0.2032 -0.3048)
							(mid -0.275042 -0.275042)
							(end -0.3048 -0.2032)
						)
						(arc
							(start -0.3048 0.2032)
							(mid -0.275042 0.275042)
							(end -0.2032 0.3048)
						)
						(arc
							(start 0.2032 0.3048)
							(mid 0.275042 0.275042)
							(end 0.3048 0.2032)
						)
					)
					(width 0)
					(fill yes)
				)
			)
		)
		(pad "2" smd custom
			(at 0 0.4445 270)
			(size 0.1524 0.1524)
			(layers "F.Cu" "F.Mask" "F.Paste")
			(net "PCIE_TX_N93")
			(options
				(clearance outline)
				(anchor circle)
			)
			(primitives
				(gr_poly
					(pts
						(arc
							(start 0.3048 -0.2032)
							(mid 0.275042 -0.275042)
							(end 0.2032 -0.3048)
						)
						(arc
							(start -0.2032 -0.3048)
							(mid -0.275042 -0.275042)
							(end -0.3048 -0.2032)
						)
						(arc
							(start -0.3048 0.2032)
							(mid -0.275042 0.275042)
							(end -0.2032 0.3048)
						)
						(arc
							(start 0.2032 0.3048)
							(mid 0.275042 0.275042)
							(end 0.3048 0.2032)
						)
					)
					(width 0)
					(fill yes)
				)
			)
		)
	)
	(footprint ""
		(layer "F.Cu")
		(at 20.6502 -194.7926 -90)
		(property "Reference" "R2106"
			(at 0 0 270)
			(layer "F.SilkS")
			(hide yes)
			(effects
				(font
					(size 1.27 1.27)
				)
			)
		)
		(property "Value" "49K9R2F-L-GP"
			(at 0.064008 -3.993896 270)
			(unlocked yes)
			(layer "F.Fab")
			(hide yes)
			(effects
				(font
					(size 1.016 1.016)
					(thickness 0.1524)
				)
			)
		)
		(property "Device Type" "R402H16"
			(at 0.064008 -5.517896 270)
			(unlocked yes)
			(layer "F.Fab")
			(hide yes)
			(effects
				(font
					(size 1.016 1.016)
					(thickness 0.1524)
				)
			)
		)
		(duplicate_pad_numbers_are_jumpers no)
		(fp_line
			(start -0.508 -0.9398)
			(end -0.508 0.9398)
			(stroke
				(width 0.1524)
				(type default)
			)
			(layer "F.SilkS")
		)
		(fp_line
			(start 0.508 -0.9398)
			(end -0.508 -0.9398)
			(stroke
				(width 0.1524)
				(type default)
			)
			(layer "F.SilkS")
		)
		(fp_rect
			(start -0.508 0.9398)
			(end 0.508 -0.9398)
			(stroke
				(width 0)
				(type default)
			)
			(fill no)
			(layer "F.CrtYd")
		)
		(fp_rect
			(start -0.508 0.9398)
			(end 0.508 -0.9398)
			(stroke
				(width 0)
				(type default)
			)
			(fill no)
			(layer "F.Fab")
		)
		(pad "1" smd custom
			(at 0 -0.4445 270)
			(size 0.1397 0.1397)
			(layers "F.Cu" "F.Mask" "F.Paste")
			(net "P12V_PCIE")
			(options
				(clearance outline)
				(anchor circle)
			)
			(primitives
				(gr_poly
					(pts
						(arc
							(start -0.1778 -0.2794)
							(mid -0.249642 -0.249642)
							(end -0.2794 -0.1778)
						)
						(arc
							(start -0.2794 0.1778)
							(mid -0.249642 0.249642)
							(end -0.1778 0.2794)
						)
						(arc
							(start 0.1778 0.2794)
							(mid 0.249642 0.249642)
							(end 0.2794 0.1778)
						)
						(arc
							(start 0.2794 -0.1778)
							(mid 0.249642 -0.249642)
							(end 0.1778 -0.2794)
						)
					)
					(width 0)
					(fill yes)
				)
			)
		)
		(pad "2" smd custom
			(at 0 0.4445 270)
			(size 0.1397 0.1397)
			(layers "F.Cu" "F.Mask" "F.Paste")
			(net "MB0_CM_OV_R")
			(options
				(clearance outline)
				(anchor circle)
			)
			(primitives
				(gr_poly
					(pts
						(arc
							(start -0.1778 -0.2794)
							(mid -0.249642 -0.249642)
							(end -0.2794 -0.1778)
						)
						(arc
							(start -0.2794 0.1778)
							(mid -0.249642 0.249642)
							(end -0.1778 0.2794)
						)
						(arc
							(start 0.1778 0.2794)
							(mid 0.249642 0.249642)
							(end 0.2794 0.1778)
						)
						(arc
							(start 0.2794 -0.1778)
							(mid 0.249642 -0.249642)
							(end 0.1778 -0.2794)
						)
					)
					(width 0)
					(fill yes)
				)
			)
		)
	)
	(footprint ""
		(layer "F.Cu")
		(at 23.876 -131.699 90)
		(property "Reference" "R363"
			(at 0 0 90)
			(layer "F.SilkS")
			(hide yes)
			(effects
				(font
					(size 1.27 1.27)
				)
			)
		)
		(property "Value" "3K3R2F-2-GP"
			(at 0.064008 -3.993896 90)
			(unlocked yes)
			(layer "F.Fab")
			(hide yes)
			(effects
				(font
					(size 1.016 1.016)
					(thickness 0.1524)
				)
			)
		)
		(property "Device Type" "R402H16"
			(at 0.064008 -5.517896 90)
			(unlocked yes)
			(layer "F.Fab")
			(hide yes)
			(effects
				(font
					(size 1.016 1.016)
					(thickness 0.1524)
				)
			)
		)
		(duplicate_pad_numbers_are_jumpers no)
		(fp_line
			(start 0.508 -0.9398)
			(end -0.508 -0.9398)
			(stroke
				(width 0.1524)
				(type default)
			)
			(layer "F.SilkS")
		)
		(fp_line
			(start -0.508 -0.9398)
			(end -0.508 0.9398)
			(stroke
				(width 0.1524)
				(type default)
			)
			(layer "F.SilkS")
		)
		(fp_rect
			(start -0.508 0.9398)
			(end 0.508 -0.9398)
			(stroke
				(width 0)
				(type default)
			)
			(fill no)
			(layer "F.CrtYd")
		)
		(fp_rect
			(start -0.508 0.9398)
			(end 0.508 -0.9398)
			(stroke
				(width 0)
				(type default)
			)
			(fill no)
			(layer "F.Fab")
		)
		(pad "1" smd custom
			(at 0 -0.4445 90)
			(size 0.1397 0.1397)
			(layers "F.Cu" "F.Mask" "F.Paste")
			(net "P3V3_STBY")
			(options
				(clearance outline)
				(anchor circle)
			)
			(primitives
				(gr_poly
					(pts
						(arc
							(start -0.1778 -0.2794)
							(mid -0.249642 -0.249642)
							(end -0.2794 -0.1778)
						)
						(arc
							(start -0.2794 0.1778)
							(mid -0.249642 0.249642)
							(end -0.1778 0.2794)
						)
						(arc
							(start 0.1778 0.2794)
							(mid 0.249642 0.249642)
							(end 0.2794 0.1778)
						)
						(arc
							(start 0.2794 -0.1778)
							(mid 0.249642 -0.249642)
							(end 0.1778 -0.2794)
						)
					)
					(width 0)
					(fill yes)
				)
			)
		)
		(pad "2" smd custom
			(at 0 0.4445 90)
			(size 0.1397 0.1397)
			(layers "F.Cu" "F.Mask" "F.Paste")
			(net "ROMA6")
			(options
				(clearance outline)
				(anchor circle)
			)
			(primitives
				(gr_poly
					(pts
						(arc
							(start -0.1778 -0.2794)
							(mid -0.249642 -0.249642)
							(end -0.2794 -0.1778)
						)
						(arc
							(start -0.2794 0.1778)
							(mid -0.249642 0.249642)
							(end -0.1778 0.2794)
						)
						(arc
							(start 0.1778 0.2794)
							(mid 0.249642 0.249642)
							(end 0.2794 0.1778)
						)
						(arc
							(start 0.2794 -0.1778)
							(mid 0.249642 -0.249642)
							(end 0.1778 -0.2794)
						)
					)
					(width 0)
					(fill yes)
				)
			)
		)
	)
)
